FILE_TYPE = CONNECTIVITY;
{Allegro Design Entry HDL 17.4-2019 S026 (4007227) 1/17/2022}
"PAGE_NUMBER" = 10;
0"NC";
1"M_A_CPU0_SA_DQ<31:0>";
2"M_A_CPU0_SB_DQ<31:0>";
3"M_A_CPU0_SA_CB<7:0>";
4"M_A_CPU0_SB_CB<7:0>";
5"M_A_CPU0_SA_DQS_DP<9:0>";
6"M_A_CPU0_SA_DQS_DN<9:0>";
7"M_A_CPU0_SB_DQS_DP<9:0>";
8"M_A_CPU0_SB_DQS_DN<9:0>";
9"M_A_CPU0_SA_CA<6:0>";
10"M_A_CPU0_SB_CA<6:0>";
11"M_A_CPU0_ALERT_N";
12"M_A_CPU0_ALERT_R_N";
13"TP_M_A_CPU0_SA_TEST39A";
14"TP_M_A_CPU0_SA_TEST40";
15"M_A_CPU0_CLK_DP<0>";
16"M_A_CPU0_CLK_DN<0>";
17"M_A_CPU0_SA_CS_N<0>";
18"M_A_CPU0_SA_CS_N<1>";
19"M_A_CPU0_SA_RSP<0>";
20"M_A_CPU0_SB_CS_N<0>";
21"M_A_CPU0_SA_PAR";
22"M_A_CPU0_SB_CS_N<1>";
23"M_A_CPU0_SB_RSP<0>";
24"M_A_CPU0_SB_PAR";
25"M_A_CPU0_RESET_N";
26"M_A_CPU0_SB_CA<6>";
27"M_A_CPU0_SA_CA<6>";
28"M_A_CPU0_SB_CA<5>";
29"M_A_CPU0_SA_CA<5>";
30"M_A_CPU0_SB_CA<4>";
31"M_A_CPU0_SA_CA<4>";
32"M_A_CPU0_SB_CA<3>";
33"M_A_CPU0_SA_CA<3>";
34"M_A_CPU0_SB_CA<2>";
35"M_A_CPU0_SA_CA<2>";
36"M_A_CPU0_SB_CA<1>";
37"M_A_CPU0_SA_CA<1>";
38"M_A_CPU0_SB_CA<0>";
39"M_A_CPU0_SA_CA<0>";
40"M_A_CPU0_SB_DQS_DN<4>";
41"M_A_CPU0_SB_DQS_DN<3>";
42"M_A_CPU0_SB_DQS_DN<2>";
43"M_A_CPU0_SB_DQS_DN<1>";
44"M_A_CPU0_SB_DQS_DN<0>";
45"M_A_CPU0_SB_DQS_DN<9>";
46"M_A_CPU0_SB_DQS_DN<8>";
47"M_A_CPU0_SB_DQS_DN<7>";
48"M_A_CPU0_SB_DQS_DN<6>";
49"M_A_CPU0_SB_DQS_DN<5>";
50"M_A_CPU0_SB_DQS_DP<9>";
51"M_A_CPU0_SB_DQS_DP<8>";
52"M_A_CPU0_SB_DQS_DP<7>";
53"M_A_CPU0_SB_DQS_DP<6>";
54"M_A_CPU0_SB_DQS_DP<5>";
55"M_A_CPU0_SB_DQS_DP<0>";
56"M_A_CPU0_SB_DQS_DP<4>";
57"M_A_CPU0_SB_DQS_DP<3>";
58"M_A_CPU0_SB_DQS_DP<2>";
59"M_A_CPU0_SB_DQS_DP<1>";
60"M_A_CPU0_SA_DQS_DN<9>";
61"M_A_CPU0_SA_DQS_DN<8>";
62"M_A_CPU0_SA_DQS_DN<6>";
63"M_A_CPU0_SA_DQS_DN<5>";
64"M_A_CPU0_SA_DQS_DN<4>";
65"M_A_CPU0_SA_DQS_DN<3>";
66"M_A_CPU0_SA_DQS_DN<2>";
67"M_A_CPU0_SA_DQS_DN<7>";
68"M_A_CPU0_SA_DQS_DN<1>";
69"M_A_CPU0_SA_DQS_DN<0>";
70"M_A_CPU0_SA_DQS_DP<6>";
71"M_A_CPU0_SA_DQS_DP<5>";
72"M_A_CPU0_SA_DQS_DP<9>";
73"M_A_CPU0_SA_DQS_DP<8>";
74"M_A_CPU0_SA_DQS_DP<7>";
75"M_A_CPU0_SA_DQS_DP<4>";
76"M_A_CPU0_SA_DQS_DP<3>";
77"M_A_CPU0_SA_DQS_DP<2>";
78"M_A_CPU0_SA_DQS_DP<1>";
79"M_A_CPU0_SA_DQS_DP<0>";
80"M_A_CPU0_SB_CB<7>";
81"M_A_CPU0_SB_CB<6>";
82"M_A_CPU0_SB_CB<5>";
83"M_A_CPU0_SB_CB<4>";
84"M_A_CPU0_SB_CB<3>";
85"M_A_CPU0_SB_CB<2>";
86"M_A_CPU0_SB_CB<1>";
87"M_A_CPU0_SA_CB<7>";
88"M_A_CPU0_SA_CB<6>";
89"M_A_CPU0_SB_CB<0>";
90"M_A_CPU0_SA_CB<5>";
91"M_A_CPU0_SA_CB<4>";
92"M_A_CPU0_SA_CB<3>";
93"M_A_CPU0_SA_CB<2>";
94"M_A_CPU0_SA_CB<1>";
95"M_A_CPU0_SA_CB<0>";
96"M_A_CPU0_SB_DQ<28>";
97"M_A_CPU0_SB_DQ<27>";
98"M_A_CPU0_SB_DQ<26>";
99"M_A_CPU0_SB_DQ<25>";
100"M_A_CPU0_SB_DQ<24>";
101"M_A_CPU0_SB_DQ<23>";
102"M_A_CPU0_SB_DQ<31>";
103"M_A_CPU0_SB_DQ<30>";
104"M_A_CPU0_SB_DQ<29>";
105"M_A_CPU0_SB_DQ<17>";
106"M_A_CPU0_SB_DQ<16>";
107"M_A_CPU0_SB_DQ<15>";
108"M_A_CPU0_SB_DQ<14>";
109"M_A_CPU0_SB_DQ<22>";
110"M_A_CPU0_SB_DQ<21>";
111"M_A_CPU0_SB_DQ<20>";
112"M_A_CPU0_SB_DQ<19>";
113"M_A_CPU0_SB_DQ<18>";
114"M_A_CPU0_SB_DQ<13>";
115"M_A_CPU0_SB_DQ<12>";
116"M_A_CPU0_SB_DQ<11>";
117"M_A_CPU0_SB_DQ<10>";
118"M_A_CPU0_SB_DQ<9>";
119"M_A_CPU0_SB_DQ<8>";
120"M_A_CPU0_SB_DQ<7>";
121"M_A_CPU0_SB_DQ<6>";
122"M_A_CPU0_SB_DQ<5>";
123"M_A_CPU0_SB_DQ<2>";
124"M_A_CPU0_SB_DQ<1>";
125"M_A_CPU0_SB_DQ<0>";
126"M_A_CPU0_SA_DQ<29>";
127"M_A_CPU0_SA_DQ<28>";
128"M_A_CPU0_SA_DQ<27>";
129"M_A_CPU0_SA_DQ<31>";
130"M_A_CPU0_SA_DQ<30>";
131"M_A_CPU0_SB_DQ<4>";
132"M_A_CPU0_SB_DQ<3>";
133"M_A_CPU0_SA_DQ<19>";
134"M_A_CPU0_SA_DQ<18>";
135"M_A_CPU0_SA_DQ<26>";
136"M_A_CPU0_SA_DQ<25>";
137"M_A_CPU0_SA_DQ<24>";
138"M_A_CPU0_SA_DQ<23>";
139"M_A_CPU0_SA_DQ<22>";
140"M_A_CPU0_SA_DQ<21>";
141"M_A_CPU0_SA_DQ<20>";
142"M_A_CPU0_SA_DQ<17>";
143"M_A_CPU0_SA_DQ<16>";
144"M_A_CPU0_SA_DQ<15>";
145"M_A_CPU0_SA_DQ<14>";
146"M_A_CPU0_SA_DQ<13>";
147"M_A_CPU0_SA_DQ<9>";
148"M_A_CPU0_SA_DQ<12>";
149"M_A_CPU0_SA_DQ<11>";
150"M_A_CPU0_SA_DQ<10>";
151"M_A_CPU0_SA_DQ<3>";
152"M_A_CPU0_SA_DQ<2>";
153"M_A_CPU0_SA_DQ<1>";
154"M_A_CPU0_SA_DQ<0>";
155"M_A_CPU0_SA_DQ<8>";
156"M_A_CPU0_SA_DQ<7>";
157"M_A_CPU0_SA_DQ<6>";
158"M_A_CPU0_SA_DQ<5>";
159"M_A_CPU0_SA_DQ<4>";
%"GENOA_SP5"
"1","(-4350,3700)","0","pure_quanta","I200";
;
LOCATION"U25"
$SEC"1"
CDS_SEC"1"
PART_TYPE"SMLF"
MATERIAL"IO"
VALUE"SOCKET6096_13568-001"
CDS_LIB"pure_quanta"
NEEDS_NO_SIZE"TRUE"
CDS_LMAN_SYM_OUTLINE"-650,2500,650,-2500"
PART_NUMBER"DGA^6000030";
"TEST40"
$PN"C60"14;
"TEST39A"
$PN"BF72"13;
"MA1_CLK_L"
$PN"BG74"0;
"MA0_CLK_L"
$PN"BD74"16;
"MA1_CLK_H"
$PN"BF74"0;
"MAB_DQS_H9"
$PN"BV74"50;
"MA0_CLK_H"
$PN"BC74"15;
"MAB_PAR"
$PN"BL74"24;
"MAA_PAR"
$PN"BC73"21;
"MAA0_CS_L0"
$PN"AV74"17;
"MAA_DATA3"
$PN"G73"151;
"MAA_DQS_H6"
$PN"R73"70;
"MAB_CA6"
$PN"BK74"26;
"MAB_DATA2"
$PN"CC74"123;
"MAB_DATA17"
$PN"CR73"105;
"MAB_DATA28"
$PN"DD74"96;
"MAB_DQS_H0"
$PN"CD74"55;
"MAB_DQS_L4"
$PN"BW73"40;
"MAA_CA6"
$PN"BB72"27;
"MAA_DATA2"
$PN"F74"152;
"MAA_DQS_H5"
$PN"J73"71;
"MAA_DQS_L9"
$PN"AM72"60;
"MAB1_RSP_L"
$PN"BR74"0;
"MAB_CA5"
$PN"BK72"28;
"MAB_CHECK7"
$PN"BV72"80;
"MAB_DATA1"
$PN"CC73"124;
"MAB_DATA16"
$PN"CP74"106;
"MAB_DATA27"
$PN"DB72"97;
"MAB_DQS_L3"
$PN"DC74"41;
"MAA_CA5"
$PN"BB74"29;
"MAA_DATA1"
$PN"F72"153;
"MAA_DQS_H4"
$PN"AL74"75;
"MAA_DQS_L8"
$PN"AF72"61;
"MAB0_RSP_L"
$PN"BP74"23;
"MAB_CA4"
$PN"BJ73"30;
"MAB_CHECK6"
$PN"BU74"81;
"MAB_DATA0"
$PN"CB74"125;
"MAB_DATA15"
$PN"CP72"107;
"MAB_DATA26"
$PN"DA74"98;
"MAB_DQS_L2"
$PN"CU74"42;
"MAA_CA4"
$PN"BA74"31;
"MAA_DATA0"
$PN"E74"154;
"MAA_DQS_H3"
$PN"AE74"76;
"MAA_DQS_L7"
$PN"Y72"67;
"MAB_CA3"
$PN"BJ74"32;
"MAB_CHECK5"
$PN"BU73"82;
"MAB_DATA14"
$PN"CN74"108;
"MAB_DATA25"
$PN"DA73"99;
"MAB_DQS_L1"
$PN"CL74"43;
"MAA_CA3"
$PN"BA73"33;
"MAA_DATA19"
$PN"W73"133;
"MAA_DQS_H2"
$PN"W74"77;
"MAA_DQS_L6"
$PN"P72"62;
"MAB_CA2"
$PN"BH74"34;
"MAB_CHECK4"
$PN"BT74"83;
"MAB_DATA13"
$PN"CN73"114;
"MAB_DATA24"
$PN"CY74"100;
"MAB_DQS_L0"
$PN"CE74"44;
"MAA_CA2"
$PN"AY72"35;
"MAA_DATA18"
$PN"V74"134;
"MAA_DATA29"
$PN"AH72"126;
"MAA_DQS_H1"
$PN"N74"78;
"MAA_DQS_L5"
$PN"H72"63;
"MAB_CA1"
$PN"BH72"36;
"MAB_CHECK3"
$PN"CB72"84;
"MAB_DATA12"
$PN"CM74"115;
"MAB_DATA23"
$PN"CY72"101;
"MAA_CA1"
$PN"AY74"37;
"MAA_DATA17"
$PN"V72"142;
"MAA_DATA28"
$PN"AG74"127;
"MAA_DQS_H0"
$PN"G74"79;
"MAA_DQS_L4"
$PN"AM74"64;
"MAB_CA0"
$PN"BG73"38;
"MAB_CHECK2"
$PN"CA74"85;
"MAB_DATA11"
$PN"CK72"116;
"MAB_DATA22"
$PN"CW74"109;
"MAA1_RSP_L"
$PN"BP72"0;
"MAA_CA0"
$PN"AW74"39;
"MAA_CHECK7"
$PN"AR73"87;
"MAA_DATA16"
$PN"U74"143;
"MAA_DATA27"
$PN"AE73"128;
"MAA_DQS_L3"
$PN"AF74"65;
"MAB_CHECK1"
$PN"CA73"86;
"MAB_DATA10"
$PN"CJ74"117;
"MAB_DATA21"
$PN"CW73"110;
"MAA0_RSP_L"
$PN"BN73"19;
"MAA_CHECK6"
$PN"AP74"88;
"MAA_DATA15"
$PN"U73"144;
"MAA_DATA26"
$PN"AD74"135;
"MAA_DQS_L2"
$PN"Y74"66;
"MAB_CHECK0"
$PN"BY74"89;
"MAB_DATA20"
$PN"CV74"111;
"MAB_DATA31"
$PN"DF74"102;
"MAA_CHECK5"
$PN"AP72"90;
"MAA_DATA14"
$PN"T74"145;
"MAA_DATA25"
$PN"AD72"136;
"MAA_DQS_L1"
$PN"P74"68;
"MAB1_CS_L1"
$PN"BM74"0;
"MAB_DATA30"
$PN"DE74"103;
"MAB_DQS_H8"
$PN"DD72"51;
"MAA_CHECK4"
$PN"AN74"91;
"MAA_DATA13"
$PN"T72"146;
"MAA_DATA24"
$PN"AC74"137;
"MAA_DQS_L0"
$PN"H74"69;
"MAB0_CS_L1"
$PN"BN74"22;
"MAB1_CS_L0"
$PN"BL73"0;
"MAB_DATA9"
$PN"CJ73"118;
"MAB_DQS_H7"
$PN"CV72"52;
"MAA_CHECK3"
$PN"AL73"92;
"MAA_DATA9"
$PN"M72"147;
"MAA_DATA12"
$PN"R74"148;
"MAA_DATA23"
$PN"AC73"138;
"MAB0_CS_L0"
$PN"BM72"20;
"MAB_DATA8"
$PN"CH74"119;
"MAB_DQS_H6"
$PN"CM72"53;
"MAA_CHECK2"
$PN"AK74"93;
"MAA_DATA8"
$PN"L74"155;
"MAA_DATA11"
$PN"N73"149;
"MAA_DATA22"
$PN"AB74"139;
"MAB_DATA7"
$PN"CH72"120;
"MAB_DQS_H5"
$PN"CF72"54;
"MAB_DQS_L9"
$PN"BW74"45;
"MAA_CHECK1"
$PN"AK72"94;
"MAA_DATA7"
$PN"L73"156;
"MAA_DATA10"
$PN"M74"150;
"MAA_DATA21"
$PN"AB72"140;
"MAB_DATA6"
$PN"CG74"121;
"MAB_DQS_H4"
$PN"BY72"56;
"MAB_DQS_L8"
$PN"DC73"46;
"MAA_CHECK0"
$PN"AJ74"95;
"MAA_DATA6"
$PN"K74"157;
"MAA_DATA20"
$PN"AA74"141;
"MAA_DATA31"
$PN"AJ73"129;
"MAA_DQS_H9"
$PN"AN73"72;
"MAB_DATA5"
$PN"CG73"122;
"MAB_DQS_H3"
$PN"DB74"57;
"MAB_DQS_L7"
$PN"CU73"47;
"MAA1_CS_L1"
$PN"AV72"0;
"MAA_DATA5"
$PN"K72"158;
"MAA_DATA30"
$PN"AH74"130;
"MAA_DQS_H8"
$PN"AG73"73;
"MAB_DATA4"
$PN"CF74"131;
"MAB_DATA19"
$PN"CT72"112;
"MAB_DQS_H2"
$PN"CT74"58;
"MAB_DQS_L6"
$PN"CL73"48;
"MAA0_CS_L1"
$PN"AW73"18;
"MAA1_CS_L0"
$PN"AU74"0;
"MAA_DATA4"
$PN"J74"159;
"MAA_DQS_H7"
$PN"AA73"74;
"MAB_DATA3"
$PN"CD72"132;
"MAB_DATA18"
$PN"CR74"113;
"MAB_DATA29"
$PN"DE73"104;
"MAB_DQS_H1"
$PN"CK74"59;
"MAB_DQS_L5"
$PN"CE73"49;
"MA_RESET_L"
$PN"AT74"25;
"MA_ALERT_L"
$PN"AR74"12;
%"TAP"
"1","(-3025,6100)","0","mstr_standard","I683";
;
CDS_LIB"mstr_standard"
BODY_TYPE"PLUMBING"
HDL_TAP"TRUE";
"B \NAC \NWC"1;
"S \NAC"
BN"0"154;
%"TAP"
"1","(-3025,5950)","0","mstr_standard","I684";
;
CDS_LIB"mstr_standard"
BODY_TYPE"PLUMBING"
HDL_TAP"TRUE";
"B \NAC \NWC"1;
"S \NAC"
BN"3"151;
%"TAP"
"1","(-3025,6000)","0","mstr_standard","I685";
;
CDS_LIB"mstr_standard"
BODY_TYPE"PLUMBING"
HDL_TAP"TRUE";
"B \NAC \NWC"1;
"S \NAC"
BN"2"152;
%"TAP"
"1","(-3025,6050)","0","mstr_standard","I686";
;
CDS_LIB"mstr_standard"
BODY_TYPE"PLUMBING"
HDL_TAP"TRUE";
"B \NAC \NWC"1;
"S \NAC"
BN"1"153;
%"TAP"
"1","(-3025,5900)","0","mstr_standard","I687";
;
CDS_LIB"mstr_standard"
BODY_TYPE"PLUMBING"
HDL_TAP"TRUE";
"B \NAC \NWC"1;
"S \NAC"
BN"4"159;
%"TAP"
"1","(-3025,5850)","0","mstr_standard","I688";
;
CDS_LIB"mstr_standard"
BODY_TYPE"PLUMBING"
HDL_TAP"TRUE";
"B \NAC \NWC"1;
"S \NAC"
BN"5"158;
%"TAP"
"1","(-3025,5650)","0","mstr_standard","I689";
;
CDS_LIB"mstr_standard"
BODY_TYPE"PLUMBING"
HDL_TAP"TRUE";
"B \NAC \NWC"1;
"S \NAC"
BN"8"155;
%"TAP"
"1","(-3025,5750)","0","mstr_standard","I690";
;
CDS_LIB"mstr_standard"
BODY_TYPE"PLUMBING"
HDL_TAP"TRUE";
"B \NAC \NWC"1;
"S \NAC"
BN"7"156;
%"TAP"
"1","(-3025,5800)","0","mstr_standard","I691";
;
CDS_LIB"mstr_standard"
BODY_TYPE"PLUMBING"
HDL_TAP"TRUE";
"B \NAC \NWC"1;
"S \NAC"
BN"6"157;
%"TAP"
"1","(-3025,5600)","0","mstr_standard","I692";
;
CDS_LIB"mstr_standard"
BODY_TYPE"PLUMBING"
HDL_TAP"TRUE";
"B \NAC \NWC"1;
"S \NAC"
BN"9"147;
%"TAP"
"1","(-3025,5400)","0","mstr_standard","I693";
;
CDS_LIB"mstr_standard"
BODY_TYPE"PLUMBING"
HDL_TAP"TRUE";
"B \NAC \NWC"1;
"S \NAC"
BN"13"146;
%"TAP"
"1","(-3025,5450)","0","mstr_standard","I694";
;
CDS_LIB"mstr_standard"
BODY_TYPE"PLUMBING"
HDL_TAP"TRUE";
"B \NAC \NWC"1;
"S \NAC"
BN"12"148;
%"TAP"
"1","(-3025,5500)","0","mstr_standard","I695";
;
CDS_LIB"mstr_standard"
BODY_TYPE"PLUMBING"
HDL_TAP"TRUE";
"B \NAC \NWC"1;
"S \NAC"
BN"11"149;
%"TAP"
"1","(-3025,5550)","0","mstr_standard","I696";
;
CDS_LIB"mstr_standard"
BODY_TYPE"PLUMBING"
HDL_TAP"TRUE";
"B \NAC \NWC"1;
"S \NAC"
BN"10"150;
%"TAP"
"1","(-3025,5350)","0","mstr_standard","I697";
;
CDS_LIB"mstr_standard"
BODY_TYPE"PLUMBING"
HDL_TAP"TRUE";
"B \NAC \NWC"1;
"S \NAC"
BN"14"145;
%"TAP"
"1","(-3025,5200)","0","mstr_standard","I698";
;
CDS_LIB"mstr_standard"
BODY_TYPE"PLUMBING"
HDL_TAP"TRUE";
"B \NAC \NWC"1;
"S \NAC"
BN"16"143;
%"TAP"
"1","(-3025,5150)","0","mstr_standard","I699";
;
CDS_LIB"mstr_standard"
BODY_TYPE"PLUMBING"
HDL_TAP"TRUE";
"B \NAC \NWC"1;
"S \NAC"
BN"17"142;
%"TAP"
"1","(-3025,5300)","0","mstr_standard","I700";
;
CDS_LIB"mstr_standard"
BODY_TYPE"PLUMBING"
HDL_TAP"TRUE";
"B \NAC \NWC"1;
"S \NAC"
BN"15"144;
%"TAP"
"1","(-3025,5050)","0","mstr_standard","I701";
;
CDS_LIB"mstr_standard"
BODY_TYPE"PLUMBING"
HDL_TAP"TRUE";
"B \NAC \NWC"1;
"S \NAC"
BN"19"133;
%"TAP"
"1","(-3025,5100)","0","mstr_standard","I702";
;
CDS_LIB"mstr_standard"
BODY_TYPE"PLUMBING"
HDL_TAP"TRUE";
"B \NAC \NWC"1;
"S \NAC"
BN"18"134;
%"TAP"
"1","(-3025,4950)","0","mstr_standard","I704";
;
CDS_LIB"mstr_standard"
BODY_TYPE"PLUMBING"
HDL_TAP"TRUE";
"B \NAC \NWC"1;
"S \NAC"
BN"21"140;
%"TAP"
"1","(-3025,4900)","0","mstr_standard","I705";
;
CDS_LIB"mstr_standard"
BODY_TYPE"PLUMBING"
HDL_TAP"TRUE";
"B \NAC \NWC"1;
"S \NAC"
BN"22"139;
%"TAP"
"1","(-3025,5000)","0","mstr_standard","I706";
;
CDS_LIB"mstr_standard"
BODY_TYPE"PLUMBING"
HDL_TAP"TRUE";
"B \NAC \NWC"1;
"S \NAC"
BN"20"141;
%"TAP"
"1","(-3025,4850)","0","mstr_standard","I707";
;
CDS_LIB"mstr_standard"
BODY_TYPE"PLUMBING"
HDL_TAP"TRUE";
"B \NAC \NWC"1;
"S \NAC"
BN"23"138;
%"TAP"
"1","(-3025,4650)","0","mstr_standard","I708";
;
CDS_LIB"mstr_standard"
BODY_TYPE"PLUMBING"
HDL_TAP"TRUE";
"B \NAC \NWC"1;
"S \NAC"
BN"26"135;
%"TAP"
"1","(-3025,4700)","0","mstr_standard","I709";
;
CDS_LIB"mstr_standard"
BODY_TYPE"PLUMBING"
HDL_TAP"TRUE";
"B \NAC \NWC"1;
"S \NAC"
BN"25"136;
%"TAP"
"1","(-3025,4750)","0","mstr_standard","I710";
;
CDS_LIB"mstr_standard"
BODY_TYPE"PLUMBING"
HDL_TAP"TRUE";
"B \NAC \NWC"1;
"S \NAC"
BN"24"137;
%"TAP"
"1","(-3025,4550)","0","mstr_standard","I711";
;
CDS_LIB"mstr_standard"
BODY_TYPE"PLUMBING"
HDL_TAP"TRUE";
"B \NAC \NWC"1;
"S \NAC"
BN"28"127;
%"TAP"
"1","(-3025,4600)","0","mstr_standard","I712";
;
CDS_LIB"mstr_standard"
BODY_TYPE"PLUMBING"
HDL_TAP"TRUE";
"B \NAC \NWC"1;
"S \NAC"
BN"27"128;
%"TAP"
"1","(-3025,4400)","0","mstr_standard","I713";
;
CDS_LIB"mstr_standard"
BODY_TYPE"PLUMBING"
HDL_TAP"TRUE";
"B \NAC \NWC"1;
"S \NAC"
BN"31"129;
%"TAP"
"1","(-3025,4450)","0","mstr_standard","I714";
;
CDS_LIB"mstr_standard"
BODY_TYPE"PLUMBING"
HDL_TAP"TRUE";
"B \NAC \NWC"1;
"S \NAC"
BN"30"130;
%"TAP"
"1","(-3025,4500)","0","mstr_standard","I715";
;
CDS_LIB"mstr_standard"
BODY_TYPE"PLUMBING"
HDL_TAP"TRUE";
"B \NAC \NWC"1;
"S \NAC"
BN"29"126;
%"TAP"
"1","(-3025,4300)","0","mstr_standard","I716";
;
CDS_LIB"mstr_standard"
BODY_TYPE"PLUMBING"
HDL_TAP"TRUE";
"B \NAC \NWC"2;
"S \NAC"
BN"0"125;
%"TAP"
"1","(-3025,4150)","0","mstr_standard","I717";
;
CDS_LIB"mstr_standard"
BODY_TYPE"PLUMBING"
HDL_TAP"TRUE";
"B \NAC \NWC"2;
"S \NAC"
BN"3"132;
%"TAP"
"1","(-3025,4200)","0","mstr_standard","I718";
;
CDS_LIB"mstr_standard"
BODY_TYPE"PLUMBING"
HDL_TAP"TRUE";
"B \NAC \NWC"2;
"S \NAC"
BN"2"123;
%"TAP"
"1","(-3025,4250)","0","mstr_standard","I719";
;
CDS_LIB"mstr_standard"
BODY_TYPE"PLUMBING"
HDL_TAP"TRUE";
"B \NAC \NWC"2;
"S \NAC"
BN"1"124;
%"TAP"
"1","(-3025,4100)","0","mstr_standard","I720";
;
CDS_LIB"mstr_standard"
BODY_TYPE"PLUMBING"
HDL_TAP"TRUE";
"B \NAC \NWC"2;
"S \NAC"
BN"4"131;
%"TAP"
"1","(-3025,4050)","0","mstr_standard","I721";
;
CDS_LIB"mstr_standard"
BODY_TYPE"PLUMBING"
HDL_TAP"TRUE";
"B \NAC \NWC"2;
"S \NAC"
BN"5"122;
%"TAP"
"1","(-3025,3850)","0","mstr_standard","I722";
;
CDS_LIB"mstr_standard"
BODY_TYPE"PLUMBING"
HDL_TAP"TRUE";
"B \NAC \NWC"2;
"S \NAC"
BN"8"119;
%"TAP"
"1","(-3025,3950)","0","mstr_standard","I723";
;
CDS_LIB"mstr_standard"
BODY_TYPE"PLUMBING"
HDL_TAP"TRUE";
"B \NAC \NWC"2;
"S \NAC"
BN"7"120;
%"TAP"
"1","(-3025,4000)","0","mstr_standard","I724";
;
CDS_LIB"mstr_standard"
BODY_TYPE"PLUMBING"
HDL_TAP"TRUE";
"B \NAC \NWC"2;
"S \NAC"
BN"6"121;
%"TAP"
"1","(-3025,3800)","0","mstr_standard","I725";
;
CDS_LIB"mstr_standard"
BODY_TYPE"PLUMBING"
HDL_TAP"TRUE";
"B \NAC \NWC"2;
"S \NAC"
BN"9"118;
%"TAP"
"1","(-3025,3600)","0","mstr_standard","I726";
;
CDS_LIB"mstr_standard"
BODY_TYPE"PLUMBING"
HDL_TAP"TRUE";
"B \NAC \NWC"2;
"S \NAC"
BN"13"114;
%"TAP"
"1","(-3025,3700)","0","mstr_standard","I727";
;
CDS_LIB"mstr_standard"
BODY_TYPE"PLUMBING"
HDL_TAP"TRUE";
"B \NAC \NWC"2;
"S \NAC"
BN"11"116;
%"TAP"
"1","(-3025,3650)","0","mstr_standard","I728";
;
CDS_LIB"mstr_standard"
BODY_TYPE"PLUMBING"
HDL_TAP"TRUE";
"B \NAC \NWC"2;
"S \NAC"
BN"12"115;
%"TAP"
"1","(-3025,3750)","0","mstr_standard","I729";
;
CDS_LIB"mstr_standard"
BODY_TYPE"PLUMBING"
HDL_TAP"TRUE";
"B \NAC \NWC"2;
"S \NAC"
BN"10"117;
%"TAP"
"1","(-3025,3550)","0","mstr_standard","I730";
;
CDS_LIB"mstr_standard"
BODY_TYPE"PLUMBING"
HDL_TAP"TRUE";
"B \NAC \NWC"2;
"S \NAC"
BN"14"108;
%"TAP"
"1","(-3025,3400)","0","mstr_standard","I731";
;
CDS_LIB"mstr_standard"
BODY_TYPE"PLUMBING"
HDL_TAP"TRUE";
"B \NAC \NWC"2;
"S \NAC"
BN"16"106;
%"TAP"
"1","(-3025,3350)","0","mstr_standard","I732";
;
CDS_LIB"mstr_standard"
BODY_TYPE"PLUMBING"
HDL_TAP"TRUE";
"B \NAC \NWC"2;
"S \NAC"
BN"17"105;
%"TAP"
"1","(-3025,3500)","0","mstr_standard","I733";
;
CDS_LIB"mstr_standard"
BODY_TYPE"PLUMBING"
HDL_TAP"TRUE";
"B \NAC \NWC"2;
"S \NAC"
BN"15"107;
%"TAP"
"1","(-3025,3300)","0","mstr_standard","I734";
;
CDS_LIB"mstr_standard"
BODY_TYPE"PLUMBING"
HDL_TAP"TRUE";
"B \NAC \NWC"2;
"S \NAC"
BN"18"113;
%"TAP"
"1","(-3025,3100)","0","mstr_standard","I735";
;
CDS_LIB"mstr_standard"
BODY_TYPE"PLUMBING"
HDL_TAP"TRUE";
"B \NAC \NWC"2;
"S \NAC"
BN"22"109;
%"TAP"
"1","(-3025,3150)","0","mstr_standard","I736";
;
CDS_LIB"mstr_standard"
BODY_TYPE"PLUMBING"
HDL_TAP"TRUE";
"B \NAC \NWC"2;
"S \NAC"
BN"21"110;
%"TAP"
"1","(-3025,3200)","0","mstr_standard","I737";
;
CDS_LIB"mstr_standard"
BODY_TYPE"PLUMBING"
HDL_TAP"TRUE";
"B \NAC \NWC"2;
"S \NAC"
BN"20"111;
%"TAP"
"1","(-3025,3250)","0","mstr_standard","I738";
;
CDS_LIB"mstr_standard"
BODY_TYPE"PLUMBING"
HDL_TAP"TRUE";
"B \NAC \NWC"2;
"S \NAC"
BN"19"112;
%"TAP"
"1","(-3025,3050)","0","mstr_standard","I739";
;
CDS_LIB"mstr_standard"
BODY_TYPE"PLUMBING"
HDL_TAP"TRUE";
"B \NAC \NWC"2;
"S \NAC"
BN"23"101;
%"TAP"
"1","(-3025,2900)","0","mstr_standard","I742";
;
CDS_LIB"mstr_standard"
BODY_TYPE"PLUMBING"
HDL_TAP"TRUE";
"B \NAC \NWC"2;
"S \NAC"
BN"25"99;
%"TAP"
"1","(-3025,2850)","0","mstr_standard","I743";
;
CDS_LIB"mstr_standard"
BODY_TYPE"PLUMBING"
HDL_TAP"TRUE";
"B \NAC \NWC"2;
"S \NAC"
BN"26"98;
%"TAP"
"1","(-3025,2950)","0","mstr_standard","I744";
;
CDS_LIB"mstr_standard"
BODY_TYPE"PLUMBING"
HDL_TAP"TRUE";
"B \NAC \NWC"2;
"S \NAC"
BN"24"100;
%"TAP"
"1","(-3025,2750)","0","mstr_standard","I745";
;
CDS_LIB"mstr_standard"
BODY_TYPE"PLUMBING"
HDL_TAP"TRUE";
"B \NAC \NWC"2;
"S \NAC"
BN"28"96;
%"TAP"
"1","(-3025,2800)","0","mstr_standard","I746";
;
CDS_LIB"mstr_standard"
BODY_TYPE"PLUMBING"
HDL_TAP"TRUE";
"B \NAC \NWC"2;
"S \NAC"
BN"27"97;
%"TAP"
"1","(-3025,2600)","0","mstr_standard","I747";
;
CDS_LIB"mstr_standard"
BODY_TYPE"PLUMBING"
HDL_TAP"TRUE";
"B \NAC \NWC"2;
"S \NAC"
BN"31"102;
%"TAP"
"1","(-3025,2650)","0","mstr_standard","I748";
;
CDS_LIB"mstr_standard"
BODY_TYPE"PLUMBING"
HDL_TAP"TRUE";
"B \NAC \NWC"2;
"S \NAC"
BN"30"103;
%"TAP"
"1","(-3025,2700)","0","mstr_standard","I749";
;
CDS_LIB"mstr_standard"
BODY_TYPE"PLUMBING"
HDL_TAP"TRUE";
"B \NAC \NWC"2;
"S \NAC"
BN"29"104;
%"TAP"
"1","(-3025,2500)","0","mstr_standard","I750";
;
CDS_LIB"mstr_standard"
BODY_TYPE"PLUMBING"
HDL_TAP"TRUE";
"B \NAC \NWC"3;
"S \NAC"
BN"0"95;
%"TAP"
"1","(-3025,2400)","0","mstr_standard","I751";
;
CDS_LIB"mstr_standard"
BODY_TYPE"PLUMBING"
HDL_TAP"TRUE";
"B \NAC \NWC"3;
"S \NAC"
BN"2"93;
%"TAP"
"1","(-3025,2450)","0","mstr_standard","I752";
;
CDS_LIB"mstr_standard"
BODY_TYPE"PLUMBING"
HDL_TAP"TRUE";
"B \NAC \NWC"3;
"S \NAC"
BN"1"94;
%"TAP"
"1","(-3025,2350)","0","mstr_standard","I753";
;
CDS_LIB"mstr_standard"
BODY_TYPE"PLUMBING"
HDL_TAP"TRUE";
"B \NAC \NWC"3;
"S \NAC"
BN"3"92;
%"TAP"
"1","(-3025,2300)","0","mstr_standard","I754";
;
CDS_LIB"mstr_standard"
BODY_TYPE"PLUMBING"
HDL_TAP"TRUE";
"B \NAC \NWC"3;
"S \NAC"
BN"4"91;
%"TAP"
"1","(-3025,2250)","0","mstr_standard","I755";
;
CDS_LIB"mstr_standard"
BODY_TYPE"PLUMBING"
HDL_TAP"TRUE";
"B \NAC \NWC"3;
"S \NAC"
BN"5"90;
%"TAP"
"1","(-3025,2050)","0","mstr_standard","I756";
;
CDS_LIB"mstr_standard"
BODY_TYPE"PLUMBING"
HDL_TAP"TRUE";
"B \NAC \NWC"4;
"S \NAC"
BN"0"89;
%"TAP"
"1","(-3025,2150)","0","mstr_standard","I757";
;
CDS_LIB"mstr_standard"
BODY_TYPE"PLUMBING"
HDL_TAP"TRUE";
"B \NAC \NWC"3;
"S \NAC"
BN"7"87;
%"TAP"
"1","(-3025,2200)","0","mstr_standard","I758";
;
CDS_LIB"mstr_standard"
BODY_TYPE"PLUMBING"
HDL_TAP"TRUE";
"B \NAC \NWC"3;
"S \NAC"
BN"6"88;
%"TAP"
"1","(-3025,2000)","0","mstr_standard","I759";
;
CDS_LIB"mstr_standard"
BODY_TYPE"PLUMBING"
HDL_TAP"TRUE";
"B \NAC \NWC"4;
"S \NAC"
BN"1"86;
%"TAP"
"1","(-3025,1950)","0","mstr_standard","I760";
;
CDS_LIB"mstr_standard"
BODY_TYPE"PLUMBING"
HDL_TAP"TRUE";
"B \NAC \NWC"4;
"S \NAC"
BN"2"85;
%"TAP"
"1","(-3025,1900)","0","mstr_standard","I761";
;
CDS_LIB"mstr_standard"
BODY_TYPE"PLUMBING"
HDL_TAP"TRUE";
"B \NAC \NWC"4;
"S \NAC"
BN"3"84;
%"TAP"
"1","(-3025,1850)","0","mstr_standard","I762";
;
CDS_LIB"mstr_standard"
BODY_TYPE"PLUMBING"
HDL_TAP"TRUE";
"B \NAC \NWC"4;
"S \NAC"
BN"4"83;
%"TAP"
"1","(-3025,1800)","0","mstr_standard","I763";
;
CDS_LIB"mstr_standard"
BODY_TYPE"PLUMBING"
HDL_TAP"TRUE";
"B \NAC \NWC"4;
"S \NAC"
BN"5"82;
%"TAP"
"1","(-3025,1750)","0","mstr_standard","I764";
;
CDS_LIB"mstr_standard"
BODY_TYPE"PLUMBING"
HDL_TAP"TRUE";
"B \NAC \NWC"4;
"S \NAC"
BN"6"81;
%"TAP"
"1","(-3025,1700)","0","mstr_standard","I765";
;
CDS_LIB"mstr_standard"
BODY_TYPE"PLUMBING"
HDL_TAP"TRUE";
"B \NAC \NWC"4;
"S \NAC"
BN"7"80;
%"TAP"
"1","(-5550,6100)","2","mstr_standard","I766";
;
CDS_LIB"mstr_standard"
BODY_TYPE"PLUMBING"
HDL_TAP"TRUE";
"B \NAC \NWC"5;
"S \NAC"
BN"0"79;
%"TAP"
"1","(-5550,6000)","2","mstr_standard","I767";
;
CDS_LIB"mstr_standard"
BODY_TYPE"PLUMBING"
HDL_TAP"TRUE";
"B \NAC \NWC"5;
"S \NAC"
BN"1"78;
%"TAP"
"1","(-5550,5900)","2","mstr_standard","I768";
;
CDS_LIB"mstr_standard"
BODY_TYPE"PLUMBING"
HDL_TAP"TRUE";
"B \NAC \NWC"5;
"S \NAC"
BN"2"77;
%"TAP"
"1","(-5550,5800)","2","mstr_standard","I769";
;
CDS_LIB"mstr_standard"
BODY_TYPE"PLUMBING"
HDL_TAP"TRUE";
"B \NAC \NWC"5;
"S \NAC"
BN"3"76;
%"TAP"
"1","(-5550,5700)","2","mstr_standard","I770";
;
CDS_LIB"mstr_standard"
BODY_TYPE"PLUMBING"
HDL_TAP"TRUE";
"B \NAC \NWC"5;
"S \NAC"
BN"4"75;
%"TAP"
"1","(-5550,5600)","2","mstr_standard","I771";
;
CDS_LIB"mstr_standard"
BODY_TYPE"PLUMBING"
HDL_TAP"TRUE";
"B \NAC \NWC"5;
"S \NAC"
BN"5"71;
%"TAP"
"1","(-5550,5500)","2","mstr_standard","I772";
;
CDS_LIB"mstr_standard"
BODY_TYPE"PLUMBING"
HDL_TAP"TRUE";
"B \NAC \NWC"5;
"S \NAC"
BN"6"70;
%"TAP"
"1","(-5550,5400)","2","mstr_standard","I773";
;
CDS_LIB"mstr_standard"
BODY_TYPE"PLUMBING"
HDL_TAP"TRUE";
"B \NAC \NWC"5;
"S \NAC"
BN"7"74;
%"TAP"
"1","(-5550,5300)","2","mstr_standard","I774";
;
CDS_LIB"mstr_standard"
BODY_TYPE"PLUMBING"
HDL_TAP"TRUE";
"B \NAC \NWC"5;
"S \NAC"
BN"8"73;
%"TAP"
"1","(-5550,5200)","2","mstr_standard","I775";
;
CDS_LIB"mstr_standard"
BODY_TYPE"PLUMBING"
HDL_TAP"TRUE";
"B \NAC \NWC"5;
"S \NAC"
BN"9"72;
%"TAP"
"1","(-5750,5950)","2","mstr_standard","I776";
;
CDS_LIB"mstr_standard"
BODY_TYPE"PLUMBING"
HDL_TAP"TRUE";
"B \NAC \NWC"6;
"S \NAC"
BN"1"68;
%"TAP"
"1","(-5750,6050)","2","mstr_standard","I777";
;
CDS_LIB"mstr_standard"
BODY_TYPE"PLUMBING"
HDL_TAP"TRUE";
"B \NAC \NWC"6;
"S \NAC"
BN"0"69;
%"TAP"
"1","(-5750,5650)","2","mstr_standard","I778";
;
CDS_LIB"mstr_standard"
BODY_TYPE"PLUMBING"
HDL_TAP"TRUE";
"B \NAC \NWC"6;
"S \NAC"
BN"4"64;
%"TAP"
"1","(-5750,5750)","2","mstr_standard","I779";
;
CDS_LIB"mstr_standard"
BODY_TYPE"PLUMBING"
HDL_TAP"TRUE";
"B \NAC \NWC"6;
"S \NAC"
BN"3"65;
%"TAP"
"1","(-5750,5850)","2","mstr_standard","I780";
;
CDS_LIB"mstr_standard"
BODY_TYPE"PLUMBING"
HDL_TAP"TRUE";
"B \NAC \NWC"6;
"S \NAC"
BN"2"66;
%"TAP"
"1","(-5750,5450)","2","mstr_standard","I781";
;
CDS_LIB"mstr_standard"
BODY_TYPE"PLUMBING"
HDL_TAP"TRUE";
"B \NAC \NWC"6;
"S \NAC"
BN"6"62;
%"TAP"
"1","(-5750,5550)","2","mstr_standard","I782";
;
CDS_LIB"mstr_standard"
BODY_TYPE"PLUMBING"
HDL_TAP"TRUE";
"B \NAC \NWC"6;
"S \NAC"
BN"5"63;
%"TAP"
"1","(-5750,5150)","2","mstr_standard","I783";
;
CDS_LIB"mstr_standard"
BODY_TYPE"PLUMBING"
HDL_TAP"TRUE";
"B \NAC \NWC"6;
"S \NAC"
BN"9"60;
%"TAP"
"1","(-5750,5250)","2","mstr_standard","I784";
;
CDS_LIB"mstr_standard"
BODY_TYPE"PLUMBING"
HDL_TAP"TRUE";
"B \NAC \NWC"6;
"S \NAC"
BN"8"61;
%"TAP"
"1","(-5750,5350)","2","mstr_standard","I785";
;
CDS_LIB"mstr_standard"
BODY_TYPE"PLUMBING"
HDL_TAP"TRUE";
"B \NAC \NWC"6;
"S \NAC"
BN"7"67;
%"TAP"
"1","(-5550,5050)","2","mstr_standard","I786";
;
CDS_LIB"mstr_standard"
BODY_TYPE"PLUMBING"
HDL_TAP"TRUE";
"B \NAC \NWC"7;
"S \NAC"
BN"0"55;
%"TAP"
"1","(-5550,4950)","2","mstr_standard","I787";
;
CDS_LIB"mstr_standard"
BODY_TYPE"PLUMBING"
HDL_TAP"TRUE";
"B \NAC \NWC"7;
"S \NAC"
BN"1"59;
%"TAP"
"1","(-5550,4750)","2","mstr_standard","I788";
;
CDS_LIB"mstr_standard"
BODY_TYPE"PLUMBING"
HDL_TAP"TRUE";
"B \NAC \NWC"7;
"S \NAC"
BN"3"57;
%"TAP"
"1","(-5550,4850)","2","mstr_standard","I789";
;
CDS_LIB"mstr_standard"
BODY_TYPE"PLUMBING"
HDL_TAP"TRUE";
"B \NAC \NWC"7;
"S \NAC"
BN"2"58;
%"TAP"
"1","(-5550,4650)","2","mstr_standard","I790";
;
CDS_LIB"mstr_standard"
BODY_TYPE"PLUMBING"
HDL_TAP"TRUE";
"B \NAC \NWC"7;
"S \NAC"
BN"4"56;
%"TAP"
"1","(-5550,4550)","2","mstr_standard","I791";
;
CDS_LIB"mstr_standard"
BODY_TYPE"PLUMBING"
HDL_TAP"TRUE";
"B \NAC \NWC"7;
"S \NAC"
BN"5"54;
%"TAP"
"1","(-5550,4450)","2","mstr_standard","I792";
;
CDS_LIB"mstr_standard"
BODY_TYPE"PLUMBING"
HDL_TAP"TRUE";
"B \NAC \NWC"7;
"S \NAC"
BN"6"53;
%"TAP"
"1","(-5550,4350)","2","mstr_standard","I793";
;
CDS_LIB"mstr_standard"
BODY_TYPE"PLUMBING"
HDL_TAP"TRUE";
"B \NAC \NWC"7;
"S \NAC"
BN"7"52;
%"TAP"
"1","(-5550,4250)","2","mstr_standard","I794";
;
CDS_LIB"mstr_standard"
BODY_TYPE"PLUMBING"
HDL_TAP"TRUE";
"B \NAC \NWC"7;
"S \NAC"
BN"8"51;
%"TAP"
"1","(-5550,4150)","2","mstr_standard","I795";
;
CDS_LIB"mstr_standard"
BODY_TYPE"PLUMBING"
HDL_TAP"TRUE";
"B \NAC \NWC"7;
"S \NAC"
BN"9"50;
%"TAP"
"1","(-5750,4900)","2","mstr_standard","I796";
;
CDS_LIB"mstr_standard"
BODY_TYPE"PLUMBING"
HDL_TAP"TRUE";
"B \NAC \NWC"8;
"S \NAC"
BN"1"43;
%"TAP"
"1","(-5750,5000)","2","mstr_standard","I797";
;
CDS_LIB"mstr_standard"
BODY_TYPE"PLUMBING"
HDL_TAP"TRUE";
"B \NAC \NWC"8;
"S \NAC"
BN"0"44;
%"TAP"
"1","(-5750,4700)","2","mstr_standard","I798";
;
CDS_LIB"mstr_standard"
BODY_TYPE"PLUMBING"
HDL_TAP"TRUE";
"B \NAC \NWC"8;
"S \NAC"
BN"3"41;
%"TAP"
"1","(-5750,4800)","2","mstr_standard","I799";
;
CDS_LIB"mstr_standard"
BODY_TYPE"PLUMBING"
HDL_TAP"TRUE";
"B \NAC \NWC"8;
"S \NAC"
BN"2"42;
%"TAP"
"1","(-5750,4600)","2","mstr_standard","I800";
;
CDS_LIB"mstr_standard"
BODY_TYPE"PLUMBING"
HDL_TAP"TRUE";
"B \NAC \NWC"8;
"S \NAC"
BN"4"40;
%"TAP"
"1","(-5750,4400)","2","mstr_standard","I801";
;
CDS_LIB"mstr_standard"
BODY_TYPE"PLUMBING"
HDL_TAP"TRUE";
"B \NAC \NWC"8;
"S \NAC"
BN"6"48;
%"TAP"
"1","(-5750,4500)","2","mstr_standard","I802";
;
CDS_LIB"mstr_standard"
BODY_TYPE"PLUMBING"
HDL_TAP"TRUE";
"B \NAC \NWC"8;
"S \NAC"
BN"5"49;
%"TAP"
"1","(-5750,4100)","2","mstr_standard","I803";
;
CDS_LIB"mstr_standard"
BODY_TYPE"PLUMBING"
HDL_TAP"TRUE";
"B \NAC \NWC"8;
"S \NAC"
BN"9"45;
%"TAP"
"1","(-5750,4200)","2","mstr_standard","I804";
;
CDS_LIB"mstr_standard"
BODY_TYPE"PLUMBING"
HDL_TAP"TRUE";
"B \NAC \NWC"8;
"S \NAC"
BN"8"46;
%"TAP"
"1","(-5750,4300)","2","mstr_standard","I805";
;
CDS_LIB"mstr_standard"
BODY_TYPE"PLUMBING"
HDL_TAP"TRUE";
"B \NAC \NWC"8;
"S \NAC"
BN"7"47;
%"TAP"
"1","(-5700,3900)","2","mstr_standard","I810";
;
CDS_LIB"mstr_standard"
BODY_TYPE"PLUMBING"
HDL_TAP"TRUE";
"B \NAC \NWC"9;
"S \NAC"
BN"1"37;
%"TAP"
"1","(-5700,3950)","2","mstr_standard","I811";
;
CDS_LIB"mstr_standard"
BODY_TYPE"PLUMBING"
HDL_TAP"TRUE";
"B \NAC \NWC"9;
"S \NAC"
BN"0"39;
%"TAP"
"1","(-5700,3850)","2","mstr_standard","I812";
;
CDS_LIB"mstr_standard"
BODY_TYPE"PLUMBING"
HDL_TAP"TRUE";
"B \NAC \NWC"9;
"S \NAC"
BN"2"35;
%"TAP"
"1","(-5700,3750)","2","mstr_standard","I813";
;
CDS_LIB"mstr_standard"
BODY_TYPE"PLUMBING"
HDL_TAP"TRUE";
"B \NAC \NWC"9;
"S \NAC"
BN"4"31;
%"TAP"
"1","(-5700,3800)","2","mstr_standard","I814";
;
CDS_LIB"mstr_standard"
BODY_TYPE"PLUMBING"
HDL_TAP"TRUE";
"B \NAC \NWC"9;
"S \NAC"
BN"3"33;
%"TAP"
"1","(-5700,3650)","2","mstr_standard","I815";
;
CDS_LIB"mstr_standard"
BODY_TYPE"PLUMBING"
HDL_TAP"TRUE";
"B \NAC \NWC"9;
"S \NAC"
BN"6"27;
%"TAP"
"1","(-5700,3700)","2","mstr_standard","I816";
;
CDS_LIB"mstr_standard"
BODY_TYPE"PLUMBING"
HDL_TAP"TRUE";
"B \NAC \NWC"9;
"S \NAC"
BN"5"29;
%"TAP"
"1","(-5700,3500)","2","mstr_standard","I817";
;
CDS_LIB"mstr_standard"
BODY_TYPE"PLUMBING"
HDL_TAP"TRUE";
"B \NAC \NWC"10;
"S \NAC"
BN"1"36;
%"TAP"
"1","(-5700,3550)","2","mstr_standard","I818";
;
CDS_LIB"mstr_standard"
BODY_TYPE"PLUMBING"
HDL_TAP"TRUE";
"B \NAC \NWC"10;
"S \NAC"
BN"0"38;
%"TAP"
"1","(-5700,3350)","2","mstr_standard","I819";
;
CDS_LIB"mstr_standard"
BODY_TYPE"PLUMBING"
HDL_TAP"TRUE";
"B \NAC \NWC"10;
"S \NAC"
BN"4"30;
%"TAP"
"1","(-5700,3400)","2","mstr_standard","I820";
;
CDS_LIB"mstr_standard"
BODY_TYPE"PLUMBING"
HDL_TAP"TRUE";
"B \NAC \NWC"10;
"S \NAC"
BN"3"32;
%"TAP"
"1","(-5700,3450)","2","mstr_standard","I821";
;
CDS_LIB"mstr_standard"
BODY_TYPE"PLUMBING"
HDL_TAP"TRUE";
"B \NAC \NWC"10;
"S \NAC"
BN"2"34;
%"TAP"
"1","(-5700,3250)","2","mstr_standard","I822";
;
CDS_LIB"mstr_standard"
BODY_TYPE"PLUMBING"
HDL_TAP"TRUE";
"B \NAC \NWC"10;
"S \NAC"
BN"6"26;
%"TAP"
"1","(-5700,3300)","2","mstr_standard","I823";
;
CDS_LIB"mstr_standard"
BODY_TYPE"PLUMBING"
HDL_TAP"TRUE";
"B \NAC \NWC"10;
"S \NAC"
BN"5"28;
%"Q_RES"
"1","(-6600,2250)","0","pure_quanta","I837";
;
LOCATION"R375"
$SEC"1"
CDS_SEC"1"
TOLERANCE"1%"
VALUE"15"
PACK_TYPE"0402LF"
MATERIAL"CHIP"
WATTAGE"1/16W"
CDS_LIB"pure_quanta"
PART_NUMBER"CS01502FB03";
"B"
$PN"2"12;
"A"
$PN"1"11;
END.
